(kicad_pcb
	(version 20260206)
	(generator "pcbnew")
	(generator_version "10.0")
	(general
		(thickness 1.6)
		(legacy_teardrops no)
	)
	(paper "A4")
	(title_block
		(title "Wiwynn_Tioga_Pass_MB.brd")
		(comment 1 "Tioga Pass / footprints 1895-1895 of 4770")
	)
	(layers
		(0 "F.Cu" signal "TOP")
		(4 "In1.Cu" signal "L2GND")
		(6 "In2.Cu" signal "L3")
		(8 "In3.Cu" signal "L4GND")
		(10 "In4.Cu" signal "L5")
		(12 "In5.Cu" signal "L6GND")
		(14 "In6.Cu" signal "L7VCC")
		(16 "In7.Cu" signal "L8VCC")
		(18 "In8.Cu" signal "L9GND")
		(20 "In9.Cu" signal "L10")
		(22 "In10.Cu" signal "L11GND")
		(24 "In11.Cu" signal "L12")
		(26 "In12.Cu" signal "L13GND")
		(2 "B.Cu" signal "BOTTOM")
		(9 "F.Adhes" user "F.Adhesive")
		(11 "B.Adhes" user "B.Adhesive")
		(13 "F.Paste" user "Package Geometry/Pastemask Top")
		(15 "B.Paste" user "Package Geometry/Pastemask Bottom")
		(5 "F.SilkS" user "Ref Des/Silkscreen Top")
		(7 "B.SilkS" user "Ref Des/Silkscreen Bottom")
		(1 "F.Mask" user "Board Geometry/Soldermask Top")
		(3 "B.Mask" user "Board Geometry/Soldermask Bottom")
		(17 "Dwgs.User" user "User.Drawings")
		(19 "Cmts.User" user "User.Comments")
		(21 "Eco1.User" user "User.Eco1")
		(23 "Eco2.User" user "User.Eco2")
		(25 "Edge.Cuts" user "Board Geometry/Outline")
		(27 "Margin" user)
		(31 "F.CrtYd" user "Package Geometry/Place Bound Top")
		(29 "B.CrtYd" user "Package Geometry/Place Bound Bottom")
		(35 "F.Fab" user "Ref Des/Assembly Top")
		(33 "B.Fab" user "Ref Des/Assembly Bottom")
	)
	(footprint ""
		(layer "F.Cu")
		(at 439.722006 -31.4325 180)
		(property "Reference" "U25W5"
			(at 0 0 180)
			(layer "F.SilkS")
			(hide yes)
			(effects
				(font
					(size 1.27 1.27)
				)
			)
		)
		(property "Value" "*"
			(at -8.423656 -16.0909 180)
			(unlocked yes)
			(layer "F.Fab")
			(hide yes)
			(effects
				(font
					(size 1.27 1.016)
					(thickness 0.1524)
				)
			)
		)
		(property "Device Type" "H5AN4G6NAFR-TFC-GP_MEMORY-G2-HA"
			(at -8.423656 -17.6149 180)
			(unlocked yes)
			(layer "F.Fab")
			(hide yes)
			(effects
				(font
					(size 1.27 1.016)
					(thickness 0.1524)
				)
			)
		)
		(duplicate_pad_numbers_are_jumpers no)
		(fp_line
			(start 3.750056 6.500114)
			(end 3.750056 -6.500114)
			(stroke
				(width 0.1524)
				(type default)
			)
			(layer "F.SilkS")
		)
		(fp_line
			(start 3.750056 -6.500114)
			(end -3.750056 -6.500114)
			(stroke
				(width 0.1524)
				(type default)
			)
			(layer "F.SilkS")
		)
		(fp_line
			(start -3.750056 6.500114)
			(end 3.750056 6.500114)
			(stroke
				(width 0.1524)
				(type default)
			)
			(layer "F.SilkS")
		)
		(fp_line
			(start -3.750056 -6.500114)
			(end -3.750056 6.500114)
			(stroke
				(width 0.1524)
				(type default)
			)
			(layer "F.SilkS")
		)
		(fp_line
			(start -4.080256 -5.230114)
			(end -4.080256 -6.830314)
			(stroke
				(width 0.508)
				(type default)
			)
			(layer "F.SilkS")
		)
		(fp_line
			(start -4.080256 -6.830314)
			(end -2.480056 -6.830314)
			(stroke
				(width 0.508)
				(type default)
			)
			(layer "F.SilkS")
		)
		(fp_rect
			(start -3.750056 6.500114)
			(end 3.750056 -6.500114)
			(stroke
				(width 0)
				(type default)
			)
			(fill no)
			(layer "F.CrtYd")
		)
		(fp_poly
			(pts
				(xy -4.7498 7.5057) (xy -4.7498 -7.5057) (xy 4.7498 -7.5057) (xy 4.7498 -0.54864) (xy 3.750056 -0.54864)
				(xy 3.750056 -6.500114) (xy -3.750056 -6.500114) (xy -3.750056 6.500114) (xy 3.750056 6.500114)
				(xy 3.750056 -0.54356) (xy 4.7498 -0.54356) (xy 4.7498 7.5057)
			)
			(stroke
				(width 0)
				(type default)
			)
			(fill no)
			(layer "F.CrtYd")
		)
		(fp_rect
			(start -5.750052 8.50011)
			(end 5.750052 -8.50011)
			(stroke
				(width 0)
				(type default)
			)
			(fill no)
			(layer "F.Fab")
		)
		(pad "A1" smd circle
			(at -3.199892 -5.999988 180)
			(size 0.3556 0.3556)
			(layers "F.Cu" "F.Mask" "F.Paste")
			(net "P1V2_AUX_BMC")
		)
		(pad "A2" smd circle
			(at -2.400046 -5.999988 180)
			(size 0.3556 0.3556)
			(layers "F.Cu" "F.Mask" "F.Paste")
			(net "GND")
		)
		(pad "A3" smd circle
			(at -1.599946 -5.999988 180)
			(size 0.3556 0.3556)
			(layers "F.Cu" "F.Mask" "F.Paste")
			(net "BMC_M_DQ8")
		)
		(pad "A7" smd circle
			(at 1.599946 -5.999988 180)
			(size 0.3556 0.3556)
			(layers "F.Cu" "F.Mask" "F.Paste")
			(net "BMC_M_DQS1_DN")
		)
		(pad "A8" smd circle
			(at 2.400046 -5.999988 180)
			(size 0.3556 0.3556)
			(layers "F.Cu" "F.Mask" "F.Paste")
			(net "GND")
		)
		(pad "A9" smd circle
			(at 3.199892 -5.999988 180)
			(size 0.3556 0.3556)
			(layers "F.Cu" "F.Mask" "F.Paste")
			(net "P1V2_AUX_BMC")
		)
		(pad "B1" smd circle
			(at -3.199892 -5.199888 180)
			(size 0.3556 0.3556)
			(layers "F.Cu" "F.Mask" "F.Paste")
			(net "P2V5_AUX_BMC")
		)
		(pad "B2" smd circle
			(at -2.400046 -5.199888 180)
			(size 0.3556 0.3556)
			(layers "F.Cu" "F.Mask" "F.Paste")
			(net "GND")
		)
		(pad "B3" smd circle
			(at -1.599946 -5.199888 180)
			(size 0.3556 0.3556)
			(layers "F.Cu" "F.Mask" "F.Paste")
			(net "P1V2_AUX_BMC")
		)
		(pad "B7" smd circle
			(at 1.599946 -5.199888 180)
			(size 0.3556 0.3556)
			(layers "F.Cu" "F.Mask" "F.Paste")
			(net "BMC_M_DQS1_DP")
		)
		(pad "B8" smd circle
			(at 2.400046 -5.199888 180)
			(size 0.3556 0.3556)
			(layers "F.Cu" "F.Mask" "F.Paste")
			(net "BMC_M_DQ9")
		)
		(pad "B9" smd circle
			(at 3.199892 -5.199888 180)
			(size 0.3556 0.3556)
			(layers "F.Cu" "F.Mask" "F.Paste")
			(net "P1V2_AUX_BMC")
		)
		(pad "C1" smd circle
			(at -3.199892 -4.400042 180)
			(size 0.3556 0.3556)
			(layers "F.Cu" "F.Mask" "F.Paste")
			(net "P1V2_AUX_BMC")
		)
		(pad "C2" smd circle
			(at -2.400046 -4.400042 180)
			(size 0.3556 0.3556)
			(layers "F.Cu" "F.Mask" "F.Paste")
			(net "BMC_M_DQ12")
		)
		(pad "C3" smd circle
			(at -1.599946 -4.400042 180)
			(size 0.3556 0.3556)
			(layers "F.Cu" "F.Mask" "F.Paste")
			(net "BMC_M_DQ10")
		)
		(pad "C7" smd circle
			(at 1.599946 -4.400042 180)
			(size 0.3556 0.3556)
			(layers "F.Cu" "F.Mask" "F.Paste")
			(net "BMC_M_DQ11")
		)
		(pad "C8" smd circle
			(at 2.400046 -4.400042 180)
			(size 0.3556 0.3556)
			(layers "F.Cu" "F.Mask" "F.Paste")
			(net "BMC_M_DQ13")
		)
		(pad "C9" smd circle
			(at 3.199892 -4.400042 180)
			(size 0.3556 0.3556)
			(layers "F.Cu" "F.Mask" "F.Paste")
			(net "GND")
		)
		(pad "D1" smd circle
			(at -3.199892 -3.599942 180)
			(size 0.3556 0.3556)
			(layers "F.Cu" "F.Mask" "F.Paste")
			(net "P1V2_AUX_BMC")
		)
		(pad "D2" smd circle
			(at -2.400046 -3.599942 180)
			(size 0.3556 0.3556)
			(layers "F.Cu" "F.Mask" "F.Paste")
			(net "GND")
		)
		(pad "D3" smd circle
			(at -1.599946 -3.599942 180)
			(size 0.3556 0.3556)
			(layers "F.Cu" "F.Mask" "F.Paste")
			(net "BMC_M_DQ14")
		)
		(pad "D7" smd circle
			(at 1.599946 -3.599942 180)
			(size 0.3556 0.3556)
			(layers "F.Cu" "F.Mask" "F.Paste")
			(net "BMC_M_DQ15")
		)
		(pad "D8" smd circle
			(at 2.400046 -3.599942 180)
			(size 0.3556 0.3556)
			(layers "F.Cu" "F.Mask" "F.Paste")
			(net "GND")
		)
		(pad "D9" smd circle
			(at 3.199892 -3.599942 180)
			(size 0.3556 0.3556)
			(layers "F.Cu" "F.Mask" "F.Paste")
			(net "P1V2_AUX_BMC")
		)
		(pad "E1" smd circle
			(at -3.199892 -2.800096 180)
			(size 0.3556 0.3556)
			(layers "F.Cu" "F.Mask" "F.Paste")
			(net "GND")
		)
		(pad "E2" smd circle
			(at -2.400046 -2.800096 180)
			(size 0.3556 0.3556)
			(layers "F.Cu" "F.Mask" "F.Paste")
			(net "BMC_M_DM1")
		)
		(pad "E3" smd circle
			(at -1.599946 -2.800096 180)
			(size 0.3556 0.3556)
			(layers "F.Cu" "F.Mask" "F.Paste")
			(net "GND")
		)
		(pad "E7" smd circle
			(at 1.599946 -2.800096 180)
			(size 0.3556 0.3556)
			(layers "F.Cu" "F.Mask" "F.Paste")
			(net "BMC_M_DM0")
		)
		(pad "E8" smd circle
			(at 2.400046 -2.800096 180)
			(size 0.3556 0.3556)
			(layers "F.Cu" "F.Mask" "F.Paste")
			(net "GND")
		)
		(pad "E9" smd circle
			(at 3.199892 -2.800096 180)
			(size 0.3556 0.3556)
			(layers "F.Cu" "F.Mask" "F.Paste")
			(net "GND")
		)
		(pad "F1" smd circle
			(at -3.199892 -1.999996 180)
			(size 0.3556 0.3556)
			(layers "F.Cu" "F.Mask" "F.Paste")
			(net "GND")
		)
		(pad "F2" smd circle
			(at -2.400046 -1.999996 180)
			(size 0.3556 0.3556)
			(layers "F.Cu" "F.Mask" "F.Paste")
			(net "P1V2_AUX_BMC")
		)
		(pad "F3" smd circle
			(at -1.599946 -1.999996 180)
			(size 0.3556 0.3556)
			(layers "F.Cu" "F.Mask" "F.Paste")
			(net "BMC_M_DQS0_DN")
		)
		(pad "F7" smd circle
			(at 1.599946 -1.999996 180)
			(size 0.3556 0.3556)
			(layers "F.Cu" "F.Mask" "F.Paste")
			(net "BMC_M_DQ1")
		)
		(pad "F8" smd circle
			(at 2.400046 -1.999996 180)
			(size 0.3556 0.3556)
			(layers "F.Cu" "F.Mask" "F.Paste")
			(net "P1V2_AUX_BMC")
		)
		(pad "F9" smd circle
			(at 3.199892 -1.999996 180)
			(size 0.3556 0.3556)
			(layers "F.Cu" "F.Mask" "F.Paste")
			(net "BMC_ZQ")
		)
		(pad "G1" smd circle
			(at -3.199892 -1.199896 180)
			(size 0.3556 0.3556)
			(layers "F.Cu" "F.Mask" "F.Paste")
			(net "P1V2_AUX_BMC")
		)
		(pad "G2" smd circle
			(at -2.400046 -1.199896 180)
			(size 0.3556 0.3556)
			(layers "F.Cu" "F.Mask" "F.Paste")
			(net "BMC_M_DQ0")
		)
		(pad "G3" smd circle
			(at -1.599946 -1.199896 180)
			(size 0.3556 0.3556)
			(layers "F.Cu" "F.Mask" "F.Paste")
			(net "BMC_M_DQS0_DP")
		)
		(pad "G7" smd circle
			(at 1.599946 -1.199896 180)
			(size 0.3556 0.3556)
			(layers "F.Cu" "F.Mask" "F.Paste")
			(net "P1V2_AUX_BMC")
		)
		(pad "G8" smd circle
			(at 2.400046 -1.199896 180)
			(size 0.3556 0.3556)
			(layers "F.Cu" "F.Mask" "F.Paste")
			(net "GND")
		)
		(pad "G9" smd circle
			(at 3.199892 -1.199896 180)
			(size 0.3556 0.3556)
			(layers "F.Cu" "F.Mask" "F.Paste")
			(net "P1V2_AUX_BMC")
		)
		(pad "H1" smd circle
			(at -3.199892 -0.40005 180)
			(size 0.3556 0.3556)
			(layers "F.Cu" "F.Mask" "F.Paste")
			(net "GND")
		)
		(pad "H2" smd circle
			(at -2.400046 -0.40005 180)
			(size 0.3556 0.3556)
			(layers "F.Cu" "F.Mask" "F.Paste")
			(net "BMC_M_DQ4")
		)
		(pad "H3" smd circle
			(at -1.599946 -0.40005 180)
			(size 0.3556 0.3556)
			(layers "F.Cu" "F.Mask" "F.Paste")
			(net "BMC_M_DQ2")
		)
		(pad "H7" smd circle
			(at 1.599946 -0.40005 180)
			(size 0.3556 0.3556)
			(layers "F.Cu" "F.Mask" "F.Paste")
			(net "BMC_M_DQ3")
		)
		(pad "H8" smd circle
			(at 2.400046 -0.40005 180)
			(size 0.3556 0.3556)
			(layers "F.Cu" "F.Mask" "F.Paste")
			(net "BMC_M_DQ5")
		)
		(pad "H9" smd circle
			(at 3.199892 -0.40005 180)
			(size 0.3556 0.3556)
			(layers "F.Cu" "F.Mask" "F.Paste")
			(net "GND")
		)
		(pad "J1" smd circle
			(at -3.199892 0.40005 180)
			(size 0.3556 0.3556)
			(layers "F.Cu" "F.Mask" "F.Paste")
			(net "P1V2_AUX_BMC")
		)
		(pad "J2" smd circle
			(at -2.400046 0.40005 180)
			(size 0.3556 0.3556)
			(layers "F.Cu" "F.Mask" "F.Paste")
			(net "P1V2_AUX_BMC")
		)
		(pad "J3" smd circle
			(at -1.599946 0.40005 180)
			(size 0.3556 0.3556)
			(layers "F.Cu" "F.Mask" "F.Paste")
			(net "BMC_M_DQ6")
		)
		(pad "J7" smd circle
			(at 1.599946 0.40005 180)
			(size 0.3556 0.3556)
			(layers "F.Cu" "F.Mask" "F.Paste")
			(net "BMC_M_DQ7")
		)
		(pad "J8" smd circle
			(at 2.400046 0.40005 180)
			(size 0.3556 0.3556)
			(layers "F.Cu" "F.Mask" "F.Paste")
			(net "P1V2_AUX_BMC")
		)
		(pad "J9" smd circle
			(at 3.199892 0.40005 180)
			(size 0.3556 0.3556)
			(layers "F.Cu" "F.Mask" "F.Paste")
			(net "P1V2_AUX_BMC")
		)
		(pad "K1" smd circle
			(at -3.199892 1.199896 180)
			(size 0.3556 0.3556)
			(layers "F.Cu" "F.Mask" "F.Paste")
			(net "GND")
		)
		(pad "K2" smd circle
			(at -2.400046 1.199896 180)
			(size 0.3556 0.3556)
			(layers "F.Cu" "F.Mask" "F.Paste")
			(net "BMC_M_CKE")
		)
		(pad "K3" smd circle
			(at -1.599946 1.199896 180)
			(size 0.3556 0.3556)
			(layers "F.Cu" "F.Mask" "F.Paste")
			(net "BMC_M_ODT")
		)
		(pad "K7" smd circle
			(at 1.599946 1.199896 180)
			(size 0.3556 0.3556)
			(layers "F.Cu" "F.Mask" "F.Paste")
			(net "BMC_M_CLK_DP")
		)
		(pad "K8" smd circle
			(at 2.400046 1.199896 180)
			(size 0.3556 0.3556)
			(layers "F.Cu" "F.Mask" "F.Paste")
			(net "BMC_M_CLK_DN")
		)
		(pad "K9" smd circle
			(at 3.199892 1.199896 180)
			(size 0.3556 0.3556)
			(layers "F.Cu" "F.Mask" "F.Paste")
			(net "GND")
		)
		(pad "L1" smd circle
			(at -3.199892 1.999996 180)
			(size 0.3556 0.3556)
			(layers "F.Cu" "F.Mask" "F.Paste")
			(net "P1V2_AUX_BMC")
		)
		(pad "L2" smd circle
			(at -2.400046 1.999996 180)
			(size 0.3556 0.3556)
			(layers "F.Cu" "F.Mask" "F.Paste")
			(net "BMC_M_WE_N")
		)
		(pad "L3" smd circle
			(at -1.599946 1.999996 180)
			(size 0.3556 0.3556)
			(layers "F.Cu" "F.Mask" "F.Paste")
			(net "BMC_M_MACT_N")
		)
		(pad "L7" smd circle
			(at 1.599946 1.999996 180)
			(size 0.3556 0.3556)
			(layers "F.Cu" "F.Mask" "F.Paste")
			(net "BMC_M_CS_N")
		)
		(pad "L8" smd circle
			(at 2.400046 1.999996 180)
			(size 0.3556 0.3556)
			(layers "F.Cu" "F.Mask" "F.Paste")
			(net "BMC_M_RAS_N")
		)
		(pad "L9" smd circle
			(at 3.199892 1.999996 180)
			(size 0.3556 0.3556)
			(layers "F.Cu" "F.Mask" "F.Paste")
			(net "P1V2_AUX_BMC")
		)
		(pad "M1" smd circle
			(at -3.199892 2.800096 180)
			(size 0.3556 0.3556)
			(layers "F.Cu" "F.Mask" "F.Paste")
			(net "BMC_M_VREFCA")
		)
		(pad "M2" smd circle
			(at -2.400046 2.800096 180)
			(size 0.3556 0.3556)
			(layers "F.Cu" "F.Mask" "F.Paste")
			(net "BMC_M_BG0")
		)
		(pad "M3" smd circle
			(at -1.599946 2.800096 180)
			(size 0.3556 0.3556)
			(layers "F.Cu" "F.Mask" "F.Paste")
			(net "BMC_M_A10")
		)
		(pad "M7" smd circle
			(at 1.599946 2.800096 180)
			(size 0.3556 0.3556)
			(layers "F.Cu" "F.Mask" "F.Paste")
			(net "BMC_M_A12")
		)
		(pad "M8" smd circle
			(at 2.400046 2.800096 180)
			(size 0.3556 0.3556)
			(layers "F.Cu" "F.Mask" "F.Paste")
			(net "BMC_M_CAS_N")
		)
		(pad "M9" smd circle
			(at 3.199892 2.800096 180)
			(size 0.3556 0.3556)
			(layers "F.Cu" "F.Mask" "F.Paste")
			(net "GND")
		)
		(pad "N1" smd circle
			(at -3.199892 3.599942 180)
			(size 0.3556 0.3556)
			(layers "F.Cu" "F.Mask" "F.Paste")
			(net "GND")
		)
		(pad "N2" smd circle
			(at -2.400046 3.599942 180)
			(size 0.3556 0.3556)
			(layers "F.Cu" "F.Mask" "F.Paste")
			(net "BMC_M_BA0")
		)
		(pad "N3" smd circle
			(at -1.599946 3.599942 180)
			(size 0.3556 0.3556)
			(layers "F.Cu" "F.Mask" "F.Paste")
			(net "BMC_M_A4")
		)
		(pad "N7" smd circle
			(at 1.599946 3.599942 180)
			(size 0.3556 0.3556)
			(layers "F.Cu" "F.Mask" "F.Paste")
			(net "BMC_M_A3")
		)
		(pad "N8" smd circle
			(at 2.400046 3.599942 180)
			(size 0.3556 0.3556)
			(layers "F.Cu" "F.Mask" "F.Paste")
			(net "BMC_M_BA1")
		)
		(pad "N9" smd circle
			(at 3.199892 3.599942 180)
			(size 0.3556 0.3556)
			(layers "F.Cu" "F.Mask" "F.Paste")
			(net "GND")
		)
		(pad "P1" smd circle
			(at -3.199892 4.400042 180)
			(size 0.3556 0.3556)
			(layers "F.Cu" "F.Mask" "F.Paste")
			(net "BMC_M_RST_N")
		)
		(pad "P2" smd circle
			(at -2.400046 4.400042 180)
			(size 0.3556 0.3556)
			(layers "F.Cu" "F.Mask" "F.Paste")
			(net "BMC_M_A6")
		)
		(pad "P3" smd circle
			(at -1.599946 4.400042 180)
			(size 0.3556 0.3556)
			(layers "F.Cu" "F.Mask" "F.Paste")
			(net "BMC_M_A0")
		)
		(pad "P7" smd circle
			(at 1.599946 4.400042 180)
			(size 0.3556 0.3556)
			(layers "F.Cu" "F.Mask" "F.Paste")
			(net "BMC_M_A1")
		)
		(pad "P8" smd circle
			(at 2.400046 4.400042 180)
			(size 0.3556 0.3556)
			(layers "F.Cu" "F.Mask" "F.Paste")
			(net "BMC_M_A5")
		)
		(pad "P9" smd circle
			(at 3.199892 4.400042 180)
			(size 0.3556 0.3556)
			(layers "F.Cu" "F.Mask" "F.Paste")
			(net "BMC_M_MALERT_N")
		)
		(pad "R1" smd circle
			(at -3.199892 5.199888 180)
			(size 0.3556 0.3556)
			(layers "F.Cu" "F.Mask" "F.Paste")
			(net "P1V2_AUX_BMC")
		)
		(pad "R2" smd circle
			(at -2.400046 5.199888 180)
			(size 0.3556 0.3556)
			(layers "F.Cu" "F.Mask" "F.Paste")
			(net "BMC_M_A8")
		)
		(pad "R3" smd circle
			(at -1.599946 5.199888 180)
			(size 0.3556 0.3556)
			(layers "F.Cu" "F.Mask" "F.Paste")
			(net "BMC_M_A2")
		)
		(pad "R7" smd circle
			(at 1.599946 5.199888 180)
			(size 0.3556 0.3556)
			(layers "F.Cu" "F.Mask" "F.Paste")
			(net "BMC_M_A9")
		)
		(pad "R8" smd circle
			(at 2.400046 5.199888 180)
			(size 0.3556 0.3556)
			(layers "F.Cu" "F.Mask" "F.Paste")
			(net "BMC_M_A7")
		)
		(pad "R9" smd circle
			(at 3.199892 5.199888 180)
			(size 0.3556 0.3556)
			(layers "F.Cu" "F.Mask" "F.Paste")
			(net "P2V5_AUX_BMC")
		)
		(pad "T1" smd circle
			(at -3.199892 5.999988 180)
			(size 0.3556 0.3556)
			(layers "F.Cu" "F.Mask" "F.Paste")
			(net "GND")
		)
		(pad "T2" smd circle
			(at -2.400046 5.999988 180)
			(size 0.3556 0.3556)
			(layers "F.Cu" "F.Mask" "F.Paste")
			(net "BMC_M_A11")
		)
		(pad "T3" smd circle
			(at -1.599946 5.999988 180)
			(size 0.3556 0.3556)
			(layers "F.Cu" "F.Mask" "F.Paste")
			(net "BMC_M_PAR")
		)
		(pad "T7" smd circle
			(at 1.599946 5.999988 180)
			(size 0.3556 0.3556)
			(layers "F.Cu" "F.Mask" "F.Paste")
			(net "Net_6479")
		)
		(pad "T8" smd circle
			(at 2.400046 5.999988 180)
			(size 0.3556 0.3556)
			(layers "F.Cu" "F.Mask" "F.Paste")
			(net "BMC_M_A13")
		)
		(pad "T9" smd circle
			(at 3.199892 5.999988 180)
			(size 0.3556 0.3556)
			(layers "F.Cu" "F.Mask" "F.Paste")
			(net "P1V2_AUX_BMC")
		)
	)
)
